FILE_TYPE = MULTI_PHYS_TABLE;

PART 'SCONN3_21291035BR2'

{========================================================================================}
:VALUE                  | PART_TYPE | MATERIAL | PART_NUMBER    = STANDARD | LIFECYCLE      | PART_NUMBER   | JEDEC_TYPE     | DESCRIPTION                             | MANUFTR | MANUF_PN        | RD_CMPLS_LVL | CMPLS_LVL | CLASS | DIP_SMD | FROM_PJ      | DATA                    | FP_ECN              | EE_CHECK_LIST | CREATOR | CREATEDAY  | PSL | STATUS | ESD_CDM | ESD_HBM | ESD_MM | MSD  | PIN_LENGTH_LONG_PIN | PIN_LENGTH_SHORT_PIN ;
{========================================================================================}
 'SCONN3_212-91-035BR2' | 'SMLF'    | 'IO'     | 'DFHD03MS251'(!) = ''       | ''               | 'DFHD03MS251' |'HEADER1X3SXF'| 'CONN SMD HEADER 3P 1R MS(P2.54, H9.3)' | 'PRX'   | '212-91-035BR2' | 'EU(V1)'     | 'EU(V1)'  | 'IO'  | ''      | 'S5XQ-FRANK' | 'PRX_212-91-035BR2.pdf' | '212-91-035BR2.msg' | ''            | ''      | '20200131' | ''  | ''     | 'NA'    | 'NA'    | 'NA'   | 'NA' | '0 MILS'            | '0 MILS'            
 'SCONN3_212-91-035BR2' | 'SMLF'    | 'EMPTY'  | 'DFHD03MS251'(!) = ''       | ''               | 'DFHD03MS251' |'HEADER1X3SXF'| 'CONN SMD HEADER 3P 1R MS(P2.54, H9.3)' | 'PRX'   | '212-91-035BR2' | 'EU(V1)'     | 'EU(V1)'  | 'IO'  | ''      | 'S5XQ-FRANK' | 'PRX_212-91-035BR2.pdf' | '212-91-035BR2.msg' | ''            | ''      | '20200131' | ''  | ''     | 'NA'    | 'NA'    | 'NA'   | 'NA' | '0 MILS'            | '0 MILS'            

END_PART

END.

